FILE_TYPE = MACRO_DRAWING;
SET COLOR_WIRE YELLOW;
SET COLOR_PROP ORANGE;
SET COLOR_DOT WHITE;
SET COLOR_ARC YELLOW;
SET COLOR_BODY GREEN;
SET COLOR_NOTE PURPLE;
SET PROP_DISPLAY VALUE;
SET PAGE_NUMBER P24;
SET PATH_NUMBER P0;
FORCEADD QUANTA_TITLE_BLOCK_C..1
(5225 -3000);
FORCEPROP 0 LAST CDS_CON_LAST_MODIFIED Fri Aug 25 17:25:40 2023
J 0
(3340 -2985);
DISPLAY INVISIBLE (3340 -2985);
FORCEPROP 2 LAST Q_DEPT 
J 1
(1462 -2951);
DISPLAY 1.957447 (1462 -2951);
PAINT GREEN (1462 -2951);
FORCEPROP 1 LAST CUSTOM_TXT_CDS <CON_LAST_MODIFIED>
J 0
(3340 -2985);
DISPLAY 0.978723 (3340 -2985);
FORCEPROP 2 LAST CUSTOM_TXT_CDS <XR_PAGE_TITLE>
J 0
(-2665 2250);
DISPLAY 0.638298 (-2665 2250);
PAINT PINK (-2665 2250);
DISPLAY INVISIBLE (-2665 2250);
FORCEPROP 1 LAST CUSTOM_TXT_CDS <NAME_2>
J 0
(2050 -2950);
FORCEPROP 1 LAST CUSTOM_TXT_CDS <NAME_1>
J 0
(2050 -2825);
FORCEPROP 1 LAST CUSTOM_TXT_CDS <Q_NUMBER>
J 0
(3822 -2897);
DISPLAY 1.212766 (3822 -2897);
FORCEPROP 1 LAST CUSTOM_TXT_CDS <Q_PROJ>
J 0
(2843 -2898);
DISPLAY 1.212766 (2843 -2898);
FORCEPROP 1 LAST CUSTOM_TXT_CDS <Q_REV>
J 0
(5041 -2897);
DISPLAY 1.212766 (5041 -2897);
FORCEPROP 1 LAST CUSTOM_TXT_CDS <CON_PAGE_NUM> OF <CON_TOTAL_PAGES>
J 0
(4779 -2982);
DISPLAY 0.978723 (4779 -2982);
FORCEPROP 1 LAST Q_TITLE BMC VIDEO(REAR DP)
J 0
(-4041 -2899);
DISPLAY 2.446809 (-4041 -2899);
PAINT GREEN (-4041 -2899);
FORCEPROP 2 LAST CDS_XR_PAGE_TITLE CR-24 : @SCM_LIB.SCM(SCH_1):PAGE24
J 0
(-2665 2250);
DISPLAY 0.638298 (-2665 2250);
PAINT PINK (-2665 2250);
DISPLAY INVISIBLE (-2665 2250);
FORCEPROP 2 LAST PAGE_BORDER TRUE
J 0
(-2665 2250);
DISPLAY 0.638298 (-2665 2250);
PAINT PINK (-2665 2250);
DISPLAY INVISIBLE (-2665 2250);
FORCEPROP 1 LAST CDS_LMAN_SYM_OUTLINE -9475,6775,100,-125
J 0
(5225 -3000);
DISPLAY 0.468085 (5225 -3000);
PAINT GREEN (5225 -3000);
DISPLAY INVISIBLE (5225 -3000);
FORCEPROP 2 LAST CDS_LIB pure_quanta
J 0
(5225 -3000);
DISPLAY INVISIBLE (5225 -3000);
FORCEPROP 1 LAST COMMENT_BODY TRUE
J 0
(5237 -3013);
DISPLAY 0.978723 (5237 -3013);
PAINT PEACH (5237 -3013);
DISPLAY INVISIBLE (5237 -3013);
FORCENOTE
REMOVE DISPLAY PORT FUNCTION FROM DVT.
(-3650 325) 0;
DISPLAY LEFT (-3650 325);
DISPLAY 4.914894 (-3650 325);
QUIT
